FILE_TYPE = CONNECTIVITY;
{Allegro Design Entry HDL 16.6-p007 (v16-6-112F) 10/10/2012}
"PAGE_NUMBER" = 28;
0"NC";
1"M_F_DQS_DP<17:0>";
2"M_F_DQS_DN<17:0>";
3"M_F_MA<17:0>";
4"M_F_BA<1:0>";
5"M_F_BG<1:0>";
6"M_F_CKE<3:0>";
7"M_F_CS_N<7:0>";
8"M_F_ODT<3:0>";
9"M_F_DQ<63:0>";
10"M_F_CLK_DN<3:0>";
11"M_F_CLK_DP<3:0>";
12"M_F_ECC<7:0>";
13"M_F_DQ<5>";
14"M_F_C<2>";
15"M_F_ECC<0>";
16"M_F_ECC<1>";
17"M_F_ECC<2>";
18"M_F_ECC<3>";
19"M_F_ECC<4>";
20"M_F_ECC<5>";
21"M_F_ECC<6>";
22"M_F_ECC<7>";
23"M_F_DQ<0>";
24"M_F_DQ<1>";
25"M_F_DQ<2>";
26"M_F_DQ<3>";
27"M_F_DQ<4>";
28"M_F_DQ<6>";
29"M_F_DQ<7>";
30"M_F_DQ<8>";
31"M_F_DQ<9>";
32"M_F_DQ<10>";
33"M_F_CLK_DP<0>";
34"M_F_CLK_DP<1>";
35"M_F_CLK_DP<2>";
36"M_F_CLK_DP<3>";
37"M_F_CLK_DN<0>";
38"M_F_CLK_DN<1>";
39"M_F_CLK_DN<2>";
40"M_F_CLK_DN<3>";
41"M_F_DQ<11>";
42"M_F_DQ<12>";
43"M_F_DQ<13>";
44"M_F_DQ<14>";
45"M_F_DQ<15>";
46"M_F_DQ<16>";
47"M_F_DQ<17>";
48"M_F_DQ<18>";
49"M_F_DQ<19>";
50"M_F_DQ<20>";
51"M_F_DQ<21>";
52"M_F_DQ<22>";
53"M_F_DQ<23>";
54"M_F_DQ<24>";
55"M_F_DQ<25>";
56"M_F_DQ<26>";
57"M_F_DQ<27>";
58"M_F_DQ<28>";
59"M_F_DQ<29>";
60"M_F_DQ<30>";
61"M_F_DQ<31>";
62"M_F_DQ<32>";
63"M_F_DQ<33>";
64"M_F_DQ<34>";
65"M_F_DQ<35>";
66"M_F_DQ<36>";
67"M_F_DQ<37>";
68"M_F_DQ<38>";
69"M_F_DQ<39>";
70"M_F_DQ<40>";
71"M_F_DQ<41>";
72"M_F_DQ<42>";
73"M_F_DQ<43>";
74"M_F_DQ<44>";
75"M_F_DQ<45>";
76"M_F_DQ<46>";
77"M_F_DQ<47>";
78"M_F_DQ<48>";
79"M_F_DQ<49>";
80"M_F_DQ<50>";
81"M_F_DQ<51>";
82"M_F_DQ<52>";
83"M_F_DQ<53>";
84"M_F_DQ<54>";
85"M_F_DQ<55>";
86"M_F_DQ<56>";
87"M_F_DQ<57>";
88"M_F_DQ<58>";
89"M_F_DQ<59>";
90"M_F_DQ<60>";
91"M_F_DQ<61>";
92"M_F_DQ<62>";
93"M_F_DQ<63>";
94"M_F_ODT<0>";
95"M_F_ODT<1>";
96"M_F_ODT<2>";
97"M_F_ODT<3>";
98"M_F_MA<0>";
99"M_F_MA<1>";
100"M_F_MA<2>";
101"M_F_CS_N<0>";
102"M_F_CS_N<1>";
103"M_F_CS_N<2>";
104"M_F_CS_N<3>";
105"M_F_CS_N<4>";
106"M_F_CS_N<5>";
107"M_F_CS_N<6>";
108"M_F_CS_N<7>";
109"M_F_CKE<0>";
110"M_F_CKE<1>";
111"M_F_CKE<2>";
112"M_F_CKE<3>";
113"M_F_BG<0>";
114"M_F_BG<1>";
115"M_F_BA<0>";
116"M_F_BA<1>";
117"M_F_ALERT_N";
118"M_F_PAR";
119"M_F_ACT_N";
120"M_F_MA<3>";
121"M_F_MA<4>";
122"M_F_MA<5>";
123"M_F_MA<6>";
124"M_F_MA<7>";
125"M_F_MA<8>";
126"M_F_MA<9>";
127"M_F_MA<10>";
128"M_F_MA<11>";
129"M_F_MA<12>";
130"M_F_MA<13>";
131"M_F_MA<14>";
132"M_F_MA<15>";
133"M_F_MA<16>";
134"M_F_MA<17>";
135"M_F_DQS_DP<0>";
136"M_F_DQS_DP<1>";
137"M_F_DQS_DP<2>";
138"M_F_DQS_DP<3>";
139"M_F_DQS_DP<4>";
140"M_F_DQS_DP<5>";
141"M_F_DQS_DN<0>";
142"M_F_DQS_DN<1>";
143"M_F_DQS_DN<2>";
144"M_F_DQS_DN<3>";
145"M_F_DQS_DN<4>";
146"M_F_DQS_DN<5>";
147"M_F_DQS_DN<6>";
148"M_F_DQS_DN<7>";
149"M_F_DQS_DN<8>";
150"M_F_DQS_DN<9>";
151"M_F_DQS_DN<10>";
152"M_F_DQS_DN<11>";
153"M_F_DQS_DN<12>";
154"M_F_DQS_DN<13>";
155"M_F_DQS_DN<14>";
156"M_F_DQS_DN<15>";
157"M_F_DQS_DN<16>";
158"M_F_DQS_DN<17>";
159"M_F_DQS_DP<6>";
160"M_F_DQS_DP<7>";
161"M_F_DQS_DP<8>";
162"M_F_DQS_DP<9>";
163"M_F_DQS_DP<10>";
164"M_F_DQS_DP<11>";
165"M_F_DQS_DP<12>";
166"M_F_DQS_DP<13>";
167"M_F_DQS_DP<14>";
168"M_F_DQS_DP<15>";
169"M_F_DQS_DP<16>";
170"M_F_DQS_DP<17>";
%"TAP"
"6","(-5575,875)","0","mstr_standard","I10";
;
HDL_TAP"TRUE"
BODY_TYPE"PLUMBING"
CDS_LIB"mstr_standard";
"B \NAC \NWC"11;
"S \NAC"
BN"1"34;
%"TAP"
"6","(-2850,1425)","2","mstr_standard","I100";
;
HDL_TAP"TRUE"
BODY_TYPE"PLUMBING"
CDS_LIB"mstr_standard";
"B \NAC \NWC"8;
"S \NAC"
BN"0"94;
%"TAP"
"6","(-2850,1575)","2","mstr_standard","I101";
;
HDL_TAP"TRUE"
BODY_TYPE"PLUMBING"
CDS_LIB"mstr_standard";
"B \NAC \NWC"8;
"S \NAC"
BN"3"97;
%"TAP"
"6","(-2850,1525)","2","mstr_standard","I102";
;
HDL_TAP"TRUE"
BODY_TYPE"PLUMBING"
CDS_LIB"mstr_standard";
"B \NAC \NWC"8;
"S \NAC"
BN"2"96;
%"TAP"
"6","(-2850,1675)","2","mstr_standard","I103";
;
HDL_TAP"TRUE"
BODY_TYPE"PLUMBING"
CDS_LIB"mstr_standard";
"B \NAC \NWC"6;
"S \NAC"
BN"0"109;
%"TAP"
"6","(-2850,1725)","2","mstr_standard","I104";
;
HDL_TAP"TRUE"
BODY_TYPE"PLUMBING"
CDS_LIB"mstr_standard";
"B \NAC \NWC"6;
"S \NAC"
BN"1"110;
%"TAP"
"6","(-2850,1825)","2","mstr_standard","I105";
;
HDL_TAP"TRUE"
BODY_TYPE"PLUMBING"
CDS_LIB"mstr_standard";
"B \NAC \NWC"6;
"S \NAC"
BN"3"112;
%"TAP"
"6","(-2850,1775)","2","mstr_standard","I106";
;
HDL_TAP"TRUE"
BODY_TYPE"PLUMBING"
CDS_LIB"mstr_standard";
"B \NAC \NWC"6;
"S \NAC"
BN"2"111;
%"TAP"
"6","(-2850,1925)","2","mstr_standard","I107";
;
HDL_TAP"TRUE"
BODY_TYPE"PLUMBING"
CDS_LIB"mstr_standard";
"B \NAC \NWC"3;
"S \NAC"
BN"0"98;
%"TAP"
"6","(-2850,1975)","2","mstr_standard","I108";
;
HDL_TAP"TRUE"
BODY_TYPE"PLUMBING"
CDS_LIB"mstr_standard";
"B \NAC \NWC"3;
"S \NAC"
BN"1"99;
%"TAP"
"6","(-2850,2075)","2","mstr_standard","I109";
;
HDL_TAP"TRUE"
BODY_TYPE"PLUMBING"
CDS_LIB"mstr_standard";
"B \NAC \NWC"3;
"S \NAC"
BN"3"120;
%"TAP"
"6","(-5575,925)","0","mstr_standard","I11";
;
HDL_TAP"TRUE"
BODY_TYPE"PLUMBING"
CDS_LIB"mstr_standard";
"B \NAC \NWC"11;
"S \NAC"
BN"2"35;
%"TAP"
"6","(-2850,2025)","2","mstr_standard","I110";
;
HDL_TAP"TRUE"
BODY_TYPE"PLUMBING"
CDS_LIB"mstr_standard";
"B \NAC \NWC"3;
"S \NAC"
BN"2"100;
%"TAP"
"6","(-2850,2125)","2","mstr_standard","I111";
;
HDL_TAP"TRUE"
BODY_TYPE"PLUMBING"
CDS_LIB"mstr_standard";
"B \NAC \NWC"3;
"S \NAC"
BN"4"121;
%"TAP"
"6","(-2850,2175)","2","mstr_standard","I112";
;
HDL_TAP"TRUE"
BODY_TYPE"PLUMBING"
CDS_LIB"mstr_standard";
"B \NAC \NWC"3;
"S \NAC"
BN"5"122;
%"TAP"
"6","(-2850,2225)","2","mstr_standard","I113";
;
HDL_TAP"TRUE"
BODY_TYPE"PLUMBING"
CDS_LIB"mstr_standard";
"B \NAC \NWC"3;
"S \NAC"
BN"6"123;
%"TAP"
"6","(-2850,2375)","2","mstr_standard","I114";
;
HDL_TAP"TRUE"
BODY_TYPE"PLUMBING"
CDS_LIB"mstr_standard";
"B \NAC \NWC"3;
"S \NAC"
BN"9"126;
%"TAP"
"6","(-2850,2325)","2","mstr_standard","I115";
;
HDL_TAP"TRUE"
BODY_TYPE"PLUMBING"
CDS_LIB"mstr_standard";
"B \NAC \NWC"3;
"S \NAC"
BN"8"125;
%"TAP"
"6","(-2850,2275)","2","mstr_standard","I116";
;
HDL_TAP"TRUE"
BODY_TYPE"PLUMBING"
CDS_LIB"mstr_standard";
"B \NAC \NWC"3;
"S \NAC"
BN"7"124;
%"TAP"
"6","(-2850,2475)","2","mstr_standard","I117";
;
HDL_TAP"TRUE"
BODY_TYPE"PLUMBING"
CDS_LIB"mstr_standard";
"B \NAC \NWC"3;
"S \NAC"
BN"11"128;
%"TAP"
"6","(-2850,2425)","2","mstr_standard","I118";
;
HDL_TAP"TRUE"
BODY_TYPE"PLUMBING"
CDS_LIB"mstr_standard";
"B \NAC \NWC"3;
"S \NAC"
BN"10"127;
%"TAP"
"6","(-2850,2525)","2","mstr_standard","I119";
;
HDL_TAP"TRUE"
BODY_TYPE"PLUMBING"
CDS_LIB"mstr_standard";
"B \NAC \NWC"3;
"S \NAC"
BN"12"129;
%"TAP"
"6","(-5575,975)","0","mstr_standard","I12";
;
HDL_TAP"TRUE"
BODY_TYPE"PLUMBING"
CDS_LIB"mstr_standard";
"B \NAC \NWC"11;
"S \NAC"
BN"3"36;
%"TAP"
"6","(-2850,2575)","2","mstr_standard","I120";
;
HDL_TAP"TRUE"
BODY_TYPE"PLUMBING"
CDS_LIB"mstr_standard";
"B \NAC \NWC"3;
"S \NAC"
BN"13"130;
%"TAP"
"6","(-2850,2625)","2","mstr_standard","I121";
;
HDL_TAP"TRUE"
BODY_TYPE"PLUMBING"
CDS_LIB"mstr_standard";
"B \NAC \NWC"3;
"S \NAC"
BN"14"131;
%"TAP"
"6","(-2850,2725)","2","mstr_standard","I122";
;
HDL_TAP"TRUE"
BODY_TYPE"PLUMBING"
CDS_LIB"mstr_standard";
"B \NAC \NWC"3;
"S \NAC"
BN"16"133;
%"TAP"
"6","(-2850,2675)","2","mstr_standard","I123";
;
HDL_TAP"TRUE"
BODY_TYPE"PLUMBING"
CDS_LIB"mstr_standard";
"B \NAC \NWC"3;
"S \NAC"
BN"15"132;
%"TAP"
"6","(-2850,2775)","2","mstr_standard","I124";
;
HDL_TAP"TRUE"
BODY_TYPE"PLUMBING"
CDS_LIB"mstr_standard";
"B \NAC \NWC"3;
"S \NAC"
BN"17"134;
%"TAP"
"6","(-2850,2875)","2","mstr_standard","I125";
;
HDL_TAP"TRUE"
BODY_TYPE"PLUMBING"
CDS_LIB"mstr_standard";
"B \NAC \NWC"2;
"S \NAC"
BN"0"141;
%"TAP"
"6","(-2850,2975)","2","mstr_standard","I126";
;
HDL_TAP"TRUE"
BODY_TYPE"PLUMBING"
CDS_LIB"mstr_standard";
"B \NAC \NWC"2;
"S \NAC"
BN"2"143;
%"TAP"
"6","(-2850,2925)","2","mstr_standard","I127";
;
HDL_TAP"TRUE"
BODY_TYPE"PLUMBING"
CDS_LIB"mstr_standard";
"B \NAC \NWC"2;
"S \NAC"
BN"1"142;
%"TAP"
"6","(-2850,3025)","2","mstr_standard","I128";
;
HDL_TAP"TRUE"
BODY_TYPE"PLUMBING"
CDS_LIB"mstr_standard";
"B \NAC \NWC"2;
"S \NAC"
BN"3"144;
%"TAP"
"6","(-2850,3075)","2","mstr_standard","I129";
;
HDL_TAP"TRUE"
BODY_TYPE"PLUMBING"
CDS_LIB"mstr_standard";
"B \NAC \NWC"2;
"S \NAC"
BN"4"145;
%"TAP"
"6","(-5575,1075)","0","mstr_standard","I13";
;
HDL_TAP"TRUE"
BODY_TYPE"PLUMBING"
CDS_LIB"mstr_standard";
"B \NAC \NWC"12;
"S \NAC"
BN"0"15;
%"TAP"
"6","(-2850,3125)","2","mstr_standard","I130";
;
HDL_TAP"TRUE"
BODY_TYPE"PLUMBING"
CDS_LIB"mstr_standard";
"B \NAC \NWC"2;
"S \NAC"
BN"5"146;
%"TAP"
"6","(-2850,3225)","2","mstr_standard","I131";
;
HDL_TAP"TRUE"
BODY_TYPE"PLUMBING"
CDS_LIB"mstr_standard";
"B \NAC \NWC"2;
"S \NAC"
BN"7"148;
%"TAP"
"6","(-2850,3175)","2","mstr_standard","I132";
;
HDL_TAP"TRUE"
BODY_TYPE"PLUMBING"
CDS_LIB"mstr_standard";
"B \NAC \NWC"2;
"S \NAC"
BN"6"147;
%"TAP"
"6","(-2850,3275)","2","mstr_standard","I133";
;
HDL_TAP"TRUE"
BODY_TYPE"PLUMBING"
CDS_LIB"mstr_standard";
"B \NAC \NWC"2;
"S \NAC"
BN"8"149;
%"TAP"
"6","(-2850,3375)","2","mstr_standard","I134";
;
HDL_TAP"TRUE"
BODY_TYPE"PLUMBING"
CDS_LIB"mstr_standard";
"B \NAC \NWC"2;
"S \NAC"
BN"10"151;
%"TAP"
"6","(-2850,3325)","2","mstr_standard","I135";
;
HDL_TAP"TRUE"
BODY_TYPE"PLUMBING"
CDS_LIB"mstr_standard";
"B \NAC \NWC"2;
"S \NAC"
BN"9"150;
%"TAP"
"6","(-2850,3525)","2","mstr_standard","I136";
;
HDL_TAP"TRUE"
BODY_TYPE"PLUMBING"
CDS_LIB"mstr_standard";
"B \NAC \NWC"2;
"S \NAC"
BN"13"154;
%"TAP"
"6","(-2850,3425)","2","mstr_standard","I137";
;
HDL_TAP"TRUE"
BODY_TYPE"PLUMBING"
CDS_LIB"mstr_standard";
"B \NAC \NWC"2;
"S \NAC"
BN"11"152;
%"TAP"
"6","(-2850,3475)","2","mstr_standard","I138";
;
HDL_TAP"TRUE"
BODY_TYPE"PLUMBING"
CDS_LIB"mstr_standard";
"B \NAC \NWC"2;
"S \NAC"
BN"12"153;
%"TAP"
"6","(-2850,3625)","2","mstr_standard","I139";
;
HDL_TAP"TRUE"
BODY_TYPE"PLUMBING"
CDS_LIB"mstr_standard";
"B \NAC \NWC"2;
"S \NAC"
BN"15"156;
%"TAP"
"6","(-5575,1125)","0","mstr_standard","I14";
;
HDL_TAP"TRUE"
BODY_TYPE"PLUMBING"
CDS_LIB"mstr_standard";
"B \NAC \NWC"12;
"S \NAC"
BN"1"16;
%"TAP"
"6","(-2850,3575)","2","mstr_standard","I140";
;
HDL_TAP"TRUE"
BODY_TYPE"PLUMBING"
CDS_LIB"mstr_standard";
"B \NAC \NWC"2;
"S \NAC"
BN"14"155;
%"TAP"
"6","(-2850,3725)","2","mstr_standard","I141";
;
HDL_TAP"TRUE"
BODY_TYPE"PLUMBING"
CDS_LIB"mstr_standard";
"B \NAC \NWC"2;
"S \NAC"
BN"17"158;
%"TAP"
"6","(-2850,3675)","2","mstr_standard","I142";
;
HDL_TAP"TRUE"
BODY_TYPE"PLUMBING"
CDS_LIB"mstr_standard";
"B \NAC \NWC"2;
"S \NAC"
BN"16"157;
%"TAP"
"6","(-2850,3875)","2","mstr_standard","I143";
;
HDL_TAP"TRUE"
BODY_TYPE"PLUMBING"
CDS_LIB"mstr_standard";
"B \NAC \NWC"1;
"S \NAC"
BN"1"136;
%"TAP"
"6","(-2850,3825)","2","mstr_standard","I144";
;
HDL_TAP"TRUE"
BODY_TYPE"PLUMBING"
CDS_LIB"mstr_standard";
"B \NAC \NWC"1;
"S \NAC"
BN"0"135;
%"TAP"
"6","(-2850,4025)","2","mstr_standard","I145";
;
HDL_TAP"TRUE"
BODY_TYPE"PLUMBING"
CDS_LIB"mstr_standard";
"B \NAC \NWC"1;
"S \NAC"
BN"4"139;
%"TAP"
"6","(-2850,3975)","2","mstr_standard","I146";
;
HDL_TAP"TRUE"
BODY_TYPE"PLUMBING"
CDS_LIB"mstr_standard";
"B \NAC \NWC"1;
"S \NAC"
BN"3"138;
%"TAP"
"6","(-2850,3925)","2","mstr_standard","I147";
;
HDL_TAP"TRUE"
BODY_TYPE"PLUMBING"
CDS_LIB"mstr_standard";
"B \NAC \NWC"1;
"S \NAC"
BN"2"137;
%"TAP"
"6","(-5575,1175)","0","mstr_standard","I15";
;
HDL_TAP"TRUE"
BODY_TYPE"PLUMBING"
CDS_LIB"mstr_standard";
"B \NAC \NWC"12;
"S \NAC"
BN"2"17;
%"TAP"
"6","(-2850,4125)","2","mstr_standard","I158";
;
HDL_TAP"TRUE"
BODY_TYPE"PLUMBING"
CDS_LIB"mstr_standard";
"B \NAC \NWC"1;
"S \NAC"
BN"6"159;
%"TAP"
"6","(-2850,4075)","2","mstr_standard","I159";
;
HDL_TAP"TRUE"
BODY_TYPE"PLUMBING"
CDS_LIB"mstr_standard";
"B \NAC \NWC"1;
"S \NAC"
BN"5"140;
%"TAP"
"6","(-5575,1225)","0","mstr_standard","I16";
;
HDL_TAP"TRUE"
BODY_TYPE"PLUMBING"
CDS_LIB"mstr_standard";
"B \NAC \NWC"12;
"S \NAC"
BN"3"18;
%"TAP"
"6","(-2850,4175)","2","mstr_standard","I160";
;
HDL_TAP"TRUE"
BODY_TYPE"PLUMBING"
CDS_LIB"mstr_standard";
"B \NAC \NWC"1;
"S \NAC"
BN"7"160;
%"TAP"
"6","(-2850,4275)","2","mstr_standard","I161";
;
HDL_TAP"TRUE"
BODY_TYPE"PLUMBING"
CDS_LIB"mstr_standard";
"B \NAC \NWC"1;
"S \NAC"
BN"9"162;
%"TAP"
"6","(-2850,4225)","2","mstr_standard","I162";
;
HDL_TAP"TRUE"
BODY_TYPE"PLUMBING"
CDS_LIB"mstr_standard";
"B \NAC \NWC"1;
"S \NAC"
BN"8"161;
%"TAP"
"6","(-2850,4425)","2","mstr_standard","I163";
;
HDL_TAP"TRUE"
BODY_TYPE"PLUMBING"
CDS_LIB"mstr_standard";
"B \NAC \NWC"1;
"S \NAC"
BN"12"165;
%"TAP"
"6","(-2850,4375)","2","mstr_standard","I164";
;
HDL_TAP"TRUE"
BODY_TYPE"PLUMBING"
CDS_LIB"mstr_standard";
"B \NAC \NWC"1;
"S \NAC"
BN"11"164;
%"TAP"
"6","(-2850,4325)","2","mstr_standard","I165";
;
HDL_TAP"TRUE"
BODY_TYPE"PLUMBING"
CDS_LIB"mstr_standard";
"B \NAC \NWC"1;
"S \NAC"
BN"10"163;
%"TAP"
"6","(-2850,4475)","2","mstr_standard","I166";
;
HDL_TAP"TRUE"
BODY_TYPE"PLUMBING"
CDS_LIB"mstr_standard";
"B \NAC \NWC"1;
"S \NAC"
BN"13"166;
%"TAP"
"6","(-2850,4525)","2","mstr_standard","I167";
;
HDL_TAP"TRUE"
BODY_TYPE"PLUMBING"
CDS_LIB"mstr_standard";
"B \NAC \NWC"1;
"S \NAC"
BN"14"167;
%"TAP"
"6","(-2850,4575)","2","mstr_standard","I168";
;
HDL_TAP"TRUE"
BODY_TYPE"PLUMBING"
CDS_LIB"mstr_standard";
"B \NAC \NWC"1;
"S \NAC"
BN"15"168;
%"TAP"
"6","(-2850,4625)","2","mstr_standard","I169";
;
HDL_TAP"TRUE"
BODY_TYPE"PLUMBING"
CDS_LIB"mstr_standard";
"B \NAC \NWC"1;
"S \NAC"
BN"16"169;
%"TAP"
"6","(-5575,1275)","0","mstr_standard","I17";
;
HDL_TAP"TRUE"
BODY_TYPE"PLUMBING"
CDS_LIB"mstr_standard";
"B \NAC \NWC"12;
"S \NAC"
BN"4"19;
%"TAP"
"6","(-2850,4675)","2","mstr_standard","I170";
;
HDL_TAP"TRUE"
BODY_TYPE"PLUMBING"
CDS_LIB"mstr_standard";
"B \NAC \NWC"1;
"S \NAC"
BN"17"170;
%"SKX_EXT_B"
"8","(-4175,2575)","0","chpset_lib","I172";
;
CDS_SEC"8"
ROOM"CPU0"
CDS_LOCATION"U5D1"
SEC"8"
SEC_TYPE"BGA1"
CDS_LIB"chpset_lib"
PACK_TYPE"BGA1"
MATERIAL"IC"
PART_NUMBER"TBD"
LOCATION"U5D1";
"DDR5_PAR"
$PN"DK53"118;
"DDR5_ODT<0>"
$PN"DG50"94;
"DDR5_ODT<1>"
$PN"DG48"95;
"DDR5_ODT<2>"
$PN"DK49"96;
"DDR5_ODT<3>"
$PN"DF47"97;
"DDR5_MA<0>"
$PN"DF53"98;
"DDR5_MA<1>"
$PN"DC58"99;
"DDR5_MA<2>"
$PN"DD57"100;
"DDR5_MA<3>"
$PN"DG58"120;
"DDR5_MA<4>"
$PN"DJ58"121;
"DDR5_MA<5>"
$PN"DF59"122;
"DDR5_MA<6>"
$PN"DK59"123;
"DDR5_MA<7>"
$PN"DC60"124;
"DDR5_MA<8>"
$PN"DD59"125;
"DDR5_MA<9>"
$PN"DA58"126;
"DDR5_MA<10>"
$PN"DD55"127;
"DDR5_MA<11>"
$PN"DA60"128;
"DDR5_MA<12>"
$PN"DG60"129;
"DDR5_MA<13>"
$PN"DD53"130;
"DDR5_MA<14>"
$PN"DJ50"131;
"DDR5_MA<15>"
$PN"DC54"132;
"DDR5_MA<16>"
$PN"DG52"133;
"DDR5_MA<17>"
$PN"DE46"134;
"DDR5_ECC<0>"
$PN"CH71"15;
"DDR5_ECC<1>"
$PN"CM71"16;
"DDR5_ECC<2>"
$PN"CJ68"17;
"DDR5_ECC<3>"
$PN"CL68"18;
"DDR5_ECC<4>"
$PN"CJ72"19;
"DDR5_ECC<5>"
$PN"CL72"20;
"DDR5_ECC<6>"
$PN"CH69"21;
"DDR5_ECC<7>"
$PN"CM69"22;
"DDR5_DQS_DP<0>"
$PN"CR76"135;
"DDR5_DQS_DP<1>"
$PN"DE76"136;
"DDR5_DQS_DP<2>"
$PN"DK71"137;
"DDR5_DQS_DP<3>"
$PN"CT65"138;
"DDR5_DQS_DP<4>"
$PN"DJ40"139;
"DDR5_DQS_DP<5>"
$PN"DJ32"140;
"DDR5_DQS_DP<6>"
$PN"DB35"159;
"DDR5_DQS_DP<7>"
$PN"DB29"160;
"DDR5_DQS_DP<8>"
$PN"CL70"161;
"DDR5_DQS_DP<9>"
$PN"CU74"162;
"DDR5_DQS_DP<10>"
$PN"DG74"163;
"DDR5_DQS_DP<11>"
$PN"DH69"164;
"DDR5_DQS_DP<12>"
$PN"CM65"165;
"DDR5_DQS_DP<13>"
$PN"DC40"166;
"DDR5_DQS_DP<14>"
$PN"DE32"167;
"DDR5_DQS_DP<15>"
$PN"CV35"168;
"DDR5_DQS_DP<16>"
$PN"CV29"169;
"DDR5_DQS_DP<17>"
$PN"CG70"170;
"DDR5_DQS_DN<0>"
$PN"CP77"141;
"DDR5_DQS_DN<1>"
$PN"DD77"142;
"DDR5_DQS_DN<2>"
$PN"DL72"143;
"DDR5_DQS_DN<3>"
$PN"CV65"144;
"DDR5_DQS_DN<4>"
$PN"DG40"145;
"DDR5_DQS_DN<5>"
$PN"DL32"146;
"DDR5_DQS_DN<6>"
$PN"DD35"147;
"DDR5_DQS_DN<7>"
$PN"DD29"148;
"DDR5_DQS_DN<8>"
$PN"CN70"149;
"DDR5_DQS_DN<9>"
$PN"CT75"150;
"DDR5_DQS_DN<10>"
$PN"DF75"151;
"DDR5_DQS_DN<11>"
$PN"DJ70"152;
"DDR5_DQS_DN<12>"
$PN"CP65"153;
"DDR5_DQS_DN<13>"
$PN"DE40"154;
"DDR5_DQS_DN<14>"
$PN"DG32"155;
"DDR5_DQS_DN<15>"
$PN"CY35"156;
"DDR5_DQS_DN<16>"
$PN"CY29"157;
"DDR5_DQS_DN<17>"
$PN"CJ70"158;
"DDR5_DQ<0>"
$PN"CR74"23;
"DDR5_DQ<1>"
$PN"CN76"24;
"DDR5_DQ<2>"
$PN"CW76"25;
"DDR5_DQ<3>"
$PN"CV77"26;
"DDR5_DQ<4>"
$PN"CN74"27;
"DDR5_DQ<5>"
$PN"CM75"13;
"DDR5_DQ<6>"
$PN"CV75"28;
"DDR5_DQ<7>"
$PN"CT77"29;
"DDR5_DQ<8>"
$PN"DE74"30;
"DDR5_DQ<9>"
$PN"DC76"31;
"DDR5_DQ<10>"
$PN"DH75"32;
"DDR5_DQ<11>"
$PN"DJ76"41;
"DDR5_DQ<12>"
$PN"DC74"42;
"DDR5_DQ<13>"
$PN"DB75"43;
"DDR5_DQ<14>"
$PN"DF77"44;
"DDR5_DQ<15>"
$PN"DH77"45;
"DDR5_DQ<16>"
$PN"DG70"46;
"DDR5_DQ<17>"
$PN"DJ72"47;
"DDR5_DQ<18>"
$PN"DM69"48;
"DDR5_DQ<19>"
$PN"DN70"49;
"DDR5_DQ<20>"
$PN"DF71"50;
"DDR5_DQ<21>"
$PN"DG72"51;
"DDR5_DQ<22>"
$PN"DK69"52;
"DDR5_DQ<23>"
$PN"DM71"53;
"DDR5_DQ<24>"
$PN"CN66"54;
"DDR5_DQ<25>"
$PN"CU66"55;
"DDR5_DQ<26>"
$PN"CP63"56;
"DDR5_DQ<27>"
$PN"CT63"57;
"DDR5_DQ<28>"
$PN"CP67"58;
"DDR5_DQ<29>"
$PN"CT67"59;
"DDR5_DQ<30>"
$PN"CN64"60;
"DDR5_DQ<31>"
$PN"CU64"61;
"DDR5_DQ<32>"
$PN"DD41"62;
"DDR5_DQ<33>"
$PN"DG42"63;
"DDR5_DQ<34>"
$PN"DE38"64;
"DDR5_DQ<35>"
$PN"DG38"65;
"DDR5_DQ<36>"
$PN"DA42"66;
"DDR5_DQ<37>"
$PN"DE42"67;
"DDR5_DQ<38>"
$PN"DD39"68;
"DDR5_DQ<39>"
$PN"DH39"69;
"DDR5_DQ<40>"
$PN"DF33"70;
"DDR5_DQ<41>"
$PN"DK33"71;
"DDR5_DQ<42>"
$PN"DG30"72;
"DDR5_DQ<43>"
$PN"DJ30"73;
"DDR5_DQ<44>"
$PN"DG34"74;
"DDR5_DQ<45>"
$PN"DJ34"75;
"DDR5_DQ<46>"
$PN"DF31"76;
"DDR5_DQ<47>"
$PN"DK31"77;
"DDR5_DQ<48>"
$PN"CW36"78;
"DDR5_DQ<49>"
$PN"DC36"79;
"DDR5_DQ<50>"
$PN"CY33"80;
"DDR5_DQ<51>"
$PN"DB33"81;
"DDR5_DQ<52>"
$PN"CY37"82;
"DDR5_DQ<53>"
$PN"DB37"83;
"DDR5_DQ<54>"
$PN"CW34"84;
"DDR5_DQ<55>"
$PN"DC34"85;
"DDR5_DQ<56>"
$PN"CW30"86;
"DDR5_DQ<57>"
$PN"DC30"87;
"DDR5_DQ<58>"
$PN"CY27"88;
"DDR5_DQ<59>"
$PN"DB27"89;
"DDR5_DQ<60>"
$PN"CY31"90;
"DDR5_DQ<61>"
$PN"DB31"91;
"DDR5_DQ<62>"
$PN"CW28"92;
"DDR5_DQ<63>"
$PN"DC28"93;
"DDR5_CS_N<0>"
$PN"DK51"101;
"DDR5_CS_N<1>"
$PN"DF49"102;
"DDR5_CS_N<2>"
$PN"DJ46"103;
"DDR5_CS_N<3>"
$PN"DG46"104;
"DDR5_CS_N<4>"
$PN"DF51"105;
"DDR5_CS_N<5>"
$PN"DJ48"106;
"DDR5_CS_N<6>"
$PN"DM45"107;
"DDR5_CS_N<7>"
$PN"DK45"108;
"DDR5_CLK_DP<0>"
$PN"DJ54"33;
"DDR5_CLK_DP<1>"
$PN"DG54"34;
"DDR5_CLK_DP<2>"
$PN"DJ56"35;
"DDR5_CLK_DP<3>"
$PN"DG56"36;
"DDR5_CLK_DN<0>"
$PN"DK55"37;
"DDR5_CLK_DN<1>"
$PN"DF55"38;
"DDR5_CLK_DN<2>"
$PN"DK57"39;
"DDR5_CLK_DN<3>"
$PN"DF57"40;
"DDR5_CKE<0>"
$PN"DG62"109;
"DDR5_CKE<1>"
$PN"DD63"110;
"DDR5_CKE<2>"
$PN"DK63"111;
"DDR5_CKE<3>"
$PN"DF63"112;
"DDR5_CID<2>"
$PN"DF45"14;
"DDR5_BG<0>"
$PN"DA62"113;
"DDR5_BG<1>"
$PN"DF61"114;
"DDR5_BA<0>"
$PN"DJ52"115;
"DDR5_BA<1>"
$PN"DC56"116;
"DDR5_ALERT_N"
$PN"DD61"117;
"DDR5_ACT_N"
$PN"DC62"119;
%"TAP"
"6","(-5575,1325)","0","mstr_standard","I18";
;
HDL_TAP"TRUE"
BODY_TYPE"PLUMBING"
CDS_LIB"mstr_standard";
"B \NAC \NWC"12;
"S \NAC"
BN"5"20;
%"TAP"
"6","(-5575,1375)","0","mstr_standard","I19";
;
HDL_TAP"TRUE"
BODY_TYPE"PLUMBING"
CDS_LIB"mstr_standard";
"B \NAC \NWC"12;
"S \NAC"
BN"6"21;
%"TAP"
"6","(-5575,1425)","0","mstr_standard","I20";
;
HDL_TAP"TRUE"
BODY_TYPE"PLUMBING"
CDS_LIB"mstr_standard";
"B \NAC \NWC"12;
"S \NAC"
BN"7"22;
%"TAP"
"6","(-5575,1575)","0","mstr_standard","I21";
;
HDL_TAP"TRUE"
BODY_TYPE"PLUMBING"
CDS_LIB"mstr_standard";
"B \NAC \NWC"9;
"S \NAC"
BN"1"24;
%"TAP"
"6","(-5575,1525)","0","mstr_standard","I22";
;
HDL_TAP"TRUE"
BODY_TYPE"PLUMBING"
CDS_LIB"mstr_standard";
"B \NAC \NWC"9;
"S \NAC"
BN"0"23;
%"TAP"
"6","(-5575,1625)","0","mstr_standard","I23";
;
HDL_TAP"TRUE"
BODY_TYPE"PLUMBING"
CDS_LIB"mstr_standard";
"B \NAC \NWC"9;
"S \NAC"
BN"2"25;
%"TAP"
"6","(-5575,1675)","0","mstr_standard","I24";
;
HDL_TAP"TRUE"
BODY_TYPE"PLUMBING"
CDS_LIB"mstr_standard";
"B \NAC \NWC"9;
"S \NAC"
BN"3"26;
%"TAP"
"6","(-5575,1725)","0","mstr_standard","I25";
;
HDL_TAP"TRUE"
BODY_TYPE"PLUMBING"
CDS_LIB"mstr_standard";
"B \NAC \NWC"9;
"S \NAC"
BN"4"27;
%"TAP"
"6","(-5575,1775)","0","mstr_standard","I26";
;
HDL_TAP"TRUE"
BODY_TYPE"PLUMBING"
CDS_LIB"mstr_standard";
"B \NAC \NWC"9;
"S \NAC"
BN"5"13;
%"TAP"
"6","(-5575,1825)","0","mstr_standard","I27";
;
HDL_TAP"TRUE"
BODY_TYPE"PLUMBING"
CDS_LIB"mstr_standard";
"B \NAC \NWC"9;
"S \NAC"
BN"6"28;
%"TAP"
"6","(-5575,1925)","0","mstr_standard","I28";
;
HDL_TAP"TRUE"
BODY_TYPE"PLUMBING"
CDS_LIB"mstr_standard";
"B \NAC \NWC"9;
"S \NAC"
BN"8"30;
%"TAP"
"6","(-5575,1875)","0","mstr_standard","I29";
;
HDL_TAP"TRUE"
BODY_TYPE"PLUMBING"
CDS_LIB"mstr_standard";
"B \NAC \NWC"9;
"S \NAC"
BN"7"29;
%"TAP"
"6","(-5575,1975)","0","mstr_standard","I30";
;
HDL_TAP"TRUE"
BODY_TYPE"PLUMBING"
CDS_LIB"mstr_standard";
"B \NAC \NWC"9;
"S \NAC"
BN"9"31;
%"TAP"
"6","(-5575,2025)","0","mstr_standard","I32";
;
HDL_TAP"TRUE"
BODY_TYPE"PLUMBING"
CDS_LIB"mstr_standard";
"B \NAC \NWC"9;
"S \NAC"
BN"10"32;
%"TAP"
"6","(-5575,2075)","0","mstr_standard","I33";
;
HDL_TAP"TRUE"
BODY_TYPE"PLUMBING"
CDS_LIB"mstr_standard";
"B \NAC \NWC"9;
"S \NAC"
BN"11"41;
%"TAP"
"6","(-5575,2125)","0","mstr_standard","I34";
;
HDL_TAP"TRUE"
BODY_TYPE"PLUMBING"
CDS_LIB"mstr_standard";
"B \NAC \NWC"9;
"S \NAC"
BN"12"42;
%"TAP"
"6","(-5575,2175)","0","mstr_standard","I35";
;
HDL_TAP"TRUE"
BODY_TYPE"PLUMBING"
CDS_LIB"mstr_standard";
"B \NAC \NWC"9;
"S \NAC"
BN"13"43;
%"TAP"
"6","(-5575,2225)","0","mstr_standard","I36";
;
HDL_TAP"TRUE"
BODY_TYPE"PLUMBING"
CDS_LIB"mstr_standard";
"B \NAC \NWC"9;
"S \NAC"
BN"14"44;
%"TAP"
"6","(-5575,2275)","0","mstr_standard","I37";
;
HDL_TAP"TRUE"
BODY_TYPE"PLUMBING"
CDS_LIB"mstr_standard";
"B \NAC \NWC"9;
"S \NAC"
BN"15"45;
%"TAP"
"6","(-5575,2325)","0","mstr_standard","I38";
;
HDL_TAP"TRUE"
BODY_TYPE"PLUMBING"
CDS_LIB"mstr_standard";
"B \NAC \NWC"9;
"S \NAC"
BN"16"46;
%"TAP"
"6","(-5575,2375)","0","mstr_standard","I39";
;
HDL_TAP"TRUE"
BODY_TYPE"PLUMBING"
CDS_LIB"mstr_standard";
"B \NAC \NWC"9;
"S \NAC"
BN"17"47;
%"TAP"
"6","(-5575,2425)","0","mstr_standard","I40";
;
HDL_TAP"TRUE"
BODY_TYPE"PLUMBING"
CDS_LIB"mstr_standard";
"B \NAC \NWC"9;
"S \NAC"
BN"18"48;
%"TAP"
"6","(-5575,2475)","0","mstr_standard","I41";
;
HDL_TAP"TRUE"
BODY_TYPE"PLUMBING"
CDS_LIB"mstr_standard";
"B \NAC \NWC"9;
"S \NAC"
BN"19"49;
%"TAP"
"6","(-5575,2525)","0","mstr_standard","I42";
;
HDL_TAP"TRUE"
BODY_TYPE"PLUMBING"
CDS_LIB"mstr_standard";
"B \NAC \NWC"9;
"S \NAC"
BN"20"50;
%"TAP"
"6","(-5575,2575)","0","mstr_standard","I43";
;
HDL_TAP"TRUE"
BODY_TYPE"PLUMBING"
CDS_LIB"mstr_standard";
"B \NAC \NWC"9;
"S \NAC"
BN"21"51;
%"TAP"
"6","(-5575,2625)","0","mstr_standard","I44";
;
HDL_TAP"TRUE"
BODY_TYPE"PLUMBING"
CDS_LIB"mstr_standard";
"B \NAC \NWC"9;
"S \NAC"
BN"22"52;
%"TAP"
"6","(-5575,2675)","0","mstr_standard","I45";
;
HDL_TAP"TRUE"
BODY_TYPE"PLUMBING"
CDS_LIB"mstr_standard";
"B \NAC \NWC"9;
"S \NAC"
BN"23"53;
%"TAP"
"6","(-5575,2725)","0","mstr_standard","I46";
;
HDL_TAP"TRUE"
BODY_TYPE"PLUMBING"
CDS_LIB"mstr_standard";
"B \NAC \NWC"9;
"S \NAC"
BN"24"54;
%"TAP"
"6","(-5575,2825)","0","mstr_standard","I47";
;
HDL_TAP"TRUE"
BODY_TYPE"PLUMBING"
CDS_LIB"mstr_standard";
"B \NAC \NWC"9;
"S \NAC"
BN"26"56;
%"TAP"
"6","(-5575,2775)","0","mstr_standard","I48";
;
HDL_TAP"TRUE"
BODY_TYPE"PLUMBING"
CDS_LIB"mstr_standard";
"B \NAC \NWC"9;
"S \NAC"
BN"25"55;
%"TAP"
"6","(-5575,2875)","0","mstr_standard","I49";
;
HDL_TAP"TRUE"
BODY_TYPE"PLUMBING"
CDS_LIB"mstr_standard";
"B \NAC \NWC"9;
"S \NAC"
BN"27"57;
%"TAP"
"6","(-5575,625)","0","mstr_standard","I5";
;
HDL_TAP"TRUE"
BODY_TYPE"PLUMBING"
CDS_LIB"mstr_standard";
"B \NAC \NWC"10;
"S \NAC"
BN"0"37;
%"TAP"
"6","(-5575,2925)","0","mstr_standard","I50";
;
HDL_TAP"TRUE"
BODY_TYPE"PLUMBING"
CDS_LIB"mstr_standard";
"B \NAC \NWC"9;
"S \NAC"
BN"28"58;
%"TAP"
"6","(-5575,2975)","0","mstr_standard","I51";
;
HDL_TAP"TRUE"
BODY_TYPE"PLUMBING"
CDS_LIB"mstr_standard";
"B \NAC \NWC"9;
"S \NAC"
BN"29"59;
%"TAP"
"6","(-5575,3075)","0","mstr_standard","I52";
;
HDL_TAP"TRUE"
BODY_TYPE"PLUMBING"
CDS_LIB"mstr_standard";
"B \NAC \NWC"9;
"S \NAC"
BN"31"61;
%"TAP"
"6","(-5575,3025)","0","mstr_standard","I53";
;
HDL_TAP"TRUE"
BODY_TYPE"PLUMBING"
CDS_LIB"mstr_standard";
"B \NAC \NWC"9;
"S \NAC"
BN"30"60;
%"TAP"
"6","(-5575,3125)","0","mstr_standard","I54";
;
HDL_TAP"TRUE"
BODY_TYPE"PLUMBING"
CDS_LIB"mstr_standard";
"B \NAC \NWC"9;
"S \NAC"
BN"32"62;
%"TAP"
"6","(-5575,3175)","0","mstr_standard","I55";
;
HDL_TAP"TRUE"
BODY_TYPE"PLUMBING"
CDS_LIB"mstr_standard";
"B \NAC \NWC"9;
"S \NAC"
BN"33"63;
%"TAP"
"6","(-5575,3225)","0","mstr_standard","I56";
;
HDL_TAP"TRUE"
BODY_TYPE"PLUMBING"
CDS_LIB"mstr_standard";
"B \NAC \NWC"9;
"S \NAC"
BN"34"64;
%"TAP"
"6","(-5575,3275)","0","mstr_standard","I57";
;
HDL_TAP"TRUE"
BODY_TYPE"PLUMBING"
CDS_LIB"mstr_standard";
"B \NAC \NWC"9;
"S \NAC"
BN"35"65;
%"TAP"
"6","(-5575,3325)","0","mstr_standard","I58";
;
HDL_TAP"TRUE"
BODY_TYPE"PLUMBING"
CDS_LIB"mstr_standard";
"B \NAC \NWC"9;
"S \NAC"
BN"36"66;
%"TAP"
"6","(-5575,3375)","0","mstr_standard","I59";
;
HDL_TAP"TRUE"
BODY_TYPE"PLUMBING"
CDS_LIB"mstr_standard";
"B \NAC \NWC"9;
"S \NAC"
BN"37"67;
%"TAP"
"6","(-5575,675)","0","mstr_standard","I6";
;
HDL_TAP"TRUE"
BODY_TYPE"PLUMBING"
CDS_LIB"mstr_standard";
"B \NAC \NWC"10;
"S \NAC"
BN"1"38;
%"TAP"
"6","(-5575,3425)","0","mstr_standard","I60";
;
HDL_TAP"TRUE"
BODY_TYPE"PLUMBING"
CDS_LIB"mstr_standard";
"B \NAC \NWC"9;
"S \NAC"
BN"38"68;
%"TAP"
"6","(-5575,3475)","0","mstr_standard","I61";
;
HDL_TAP"TRUE"
BODY_TYPE"PLUMBING"
CDS_LIB"mstr_standard";
"B \NAC \NWC"9;
"S \NAC"
BN"39"69;
%"TAP"
"6","(-5575,3525)","0","mstr_standard","I62";
;
HDL_TAP"TRUE"
BODY_TYPE"PLUMBING"
CDS_LIB"mstr_standard";
"B \NAC \NWC"9;
"S \NAC"
BN"40"70;
%"TAP"
"6","(-5575,3575)","0","mstr_standard","I63";
;
HDL_TAP"TRUE"
BODY_TYPE"PLUMBING"
CDS_LIB"mstr_standard";
"B \NAC \NWC"9;
"S \NAC"
BN"41"71;
%"TAP"
"6","(-5575,3625)","0","mstr_standard","I64";
;
HDL_TAP"TRUE"
BODY_TYPE"PLUMBING"
CDS_LIB"mstr_standard";
"B \NAC \NWC"9;
"S \NAC"
BN"42"72;
%"TAP"
"6","(-5575,3675)","0","mstr_standard","I65";
;
HDL_TAP"TRUE"
BODY_TYPE"PLUMBING"
CDS_LIB"mstr_standard";
"B \NAC \NWC"9;
"S \NAC"
BN"43"73;
%"TAP"
"6","(-5575,3725)","0","mstr_standard","I66";
;
HDL_TAP"TRUE"
BODY_TYPE"PLUMBING"
CDS_LIB"mstr_standard";
"B \NAC \NWC"9;
"S \NAC"
BN"44"74;
%"TAP"
"6","(-5575,3775)","0","mstr_standard","I67";
;
HDL_TAP"TRUE"
BODY_TYPE"PLUMBING"
CDS_LIB"mstr_standard";
"B \NAC \NWC"9;
"S \NAC"
BN"45"75;
%"TAP"
"6","(-5575,3825)","0","mstr_standard","I68";
;
HDL_TAP"TRUE"
BODY_TYPE"PLUMBING"
CDS_LIB"mstr_standard";
"B \NAC \NWC"9;
"S \NAC"
BN"46"76;
%"TAP"
"6","(-5575,3875)","0","mstr_standard","I69";
;
HDL_TAP"TRUE"
BODY_TYPE"PLUMBING"
CDS_LIB"mstr_standard";
"B \NAC \NWC"9;
"S \NAC"
BN"47"77;
%"TAP"
"6","(-5575,775)","0","mstr_standard","I7";
;
HDL_TAP"TRUE"
BODY_TYPE"PLUMBING"
CDS_LIB"mstr_standard";
"B \NAC \NWC"10;
"S \NAC"
BN"3"40;
%"TAP"
"6","(-5575,3925)","0","mstr_standard","I70";
;
HDL_TAP"TRUE"
BODY_TYPE"PLUMBING"
CDS_LIB"mstr_standard";
"B \NAC \NWC"9;
"S \NAC"
BN"48"78;
%"TAP"
"6","(-5575,3975)","0","mstr_standard","I71";
;
HDL_TAP"TRUE"
BODY_TYPE"PLUMBING"
CDS_LIB"mstr_standard";
"B \NAC \NWC"9;
"S \NAC"
BN"49"79;
%"TAP"
"6","(-5575,4025)","0","mstr_standard","I72";
;
HDL_TAP"TRUE"
BODY_TYPE"PLUMBING"
CDS_LIB"mstr_standard";
"B \NAC \NWC"9;
"S \NAC"
BN"50"80;
%"TAP"
"6","(-5575,4075)","0","mstr_standard","I74";
;
HDL_TAP"TRUE"
BODY_TYPE"PLUMBING"
CDS_LIB"mstr_standard";
"B \NAC \NWC"9;
"S \NAC"
BN"51"81;
%"TAP"
"6","(-5575,4125)","0","mstr_standard","I75";
;
HDL_TAP"TRUE"
BODY_TYPE"PLUMBING"
CDS_LIB"mstr_standard";
"B \NAC \NWC"9;
"S \NAC"
BN"52"82;
%"TAP"
"6","(-5575,4175)","0","mstr_standard","I76";
;
HDL_TAP"TRUE"
BODY_TYPE"PLUMBING"
CDS_LIB"mstr_standard";
"B \NAC \NWC"9;
"S \NAC"
BN"53"83;
%"TAP"
"6","(-5575,4225)","0","mstr_standard","I77";
;
HDL_TAP"TRUE"
BODY_TYPE"PLUMBING"
CDS_LIB"mstr_standard";
"B \NAC \NWC"9;
"S \NAC"
BN"54"84;
%"TAP"
"6","(-5575,4275)","0","mstr_standard","I78";
;
HDL_TAP"TRUE"
BODY_TYPE"PLUMBING"
CDS_LIB"mstr_standard";
"B \NAC \NWC"9;
"S \NAC"
BN"55"85;
%"TAP"
"6","(-5575,4325)","0","mstr_standard","I79";
;
HDL_TAP"TRUE"
BODY_TYPE"PLUMBING"
CDS_LIB"mstr_standard";
"B \NAC \NWC"9;
"S \NAC"
BN"56"86;
%"TAP"
"6","(-5575,725)","0","mstr_standard","I8";
;
HDL_TAP"TRUE"
BODY_TYPE"PLUMBING"
CDS_LIB"mstr_standard";
"B \NAC \NWC"10;
"S \NAC"
BN"2"39;
%"TAP"
"6","(-5575,4375)","0","mstr_standard","I80";
;
HDL_TAP"TRUE"
BODY_TYPE"PLUMBING"
CDS_LIB"mstr_standard";
"B \NAC \NWC"9;
"S \NAC"
BN"57"87;
%"TAP"
"6","(-5575,4425)","0","mstr_standard","I81";
;
HDL_TAP"TRUE"
BODY_TYPE"PLUMBING"
CDS_LIB"mstr_standard";
"B \NAC \NWC"9;
"S \NAC"
BN"58"88;
%"TAP"
"6","(-5575,4475)","0","mstr_standard","I82";
;
HDL_TAP"TRUE"
BODY_TYPE"PLUMBING"
CDS_LIB"mstr_standard";
"B \NAC \NWC"9;
"S \NAC"
BN"59"89;
%"TAP"
"6","(-5575,4525)","0","mstr_standard","I83";
;
HDL_TAP"TRUE"
BODY_TYPE"PLUMBING"
CDS_LIB"mstr_standard";
"B \NAC \NWC"9;
"S \NAC"
BN"60"90;
%"TAP"
"6","(-5575,4575)","0","mstr_standard","I84";
;
HDL_TAP"TRUE"
BODY_TYPE"PLUMBING"
CDS_LIB"mstr_standard";
"B \NAC \NWC"9;
"S \NAC"
BN"61"91;
%"TAP"
"6","(-5575,4625)","0","mstr_standard","I85";
;
HDL_TAP"TRUE"
BODY_TYPE"PLUMBING"
CDS_LIB"mstr_standard";
"B \NAC \NWC"9;
"S \NAC"
BN"62"92;
%"TAP"
"6","(-5575,4675)","0","mstr_standard","I86";
;
HDL_TAP"TRUE"
BODY_TYPE"PLUMBING"
CDS_LIB"mstr_standard";
"B \NAC \NWC"9;
"S \NAC"
BN"63"93;
%"TAP"
"6","(-2850,825)","2","mstr_standard","I87";
;
HDL_TAP"TRUE"
BODY_TYPE"PLUMBING"
CDS_LIB"mstr_standard";
"B \NAC \NWC"5;
"S \NAC"
BN"0"113;
%"TAP"
"6","(-2850,775)","2","mstr_standard","I88";
;
HDL_TAP"TRUE"
BODY_TYPE"PLUMBING"
CDS_LIB"mstr_standard";
"B \NAC \NWC"4;
"S \NAC"
BN"1"116;
%"TAP"
"6","(-2850,725)","2","mstr_standard","I89";
;
HDL_TAP"TRUE"
BODY_TYPE"PLUMBING"
CDS_LIB"mstr_standard";
"B \NAC \NWC"4;
"S \NAC"
BN"0"115;
%"TAP"
"6","(-5575,825)","0","mstr_standard","I9";
;
HDL_TAP"TRUE"
BODY_TYPE"PLUMBING"
CDS_LIB"mstr_standard";
"B \NAC \NWC"11;
"S \NAC"
BN"0"33;
%"TAP"
"6","(-2850,875)","2","mstr_standard","I90";
;
HDL_TAP"TRUE"
BODY_TYPE"PLUMBING"
CDS_LIB"mstr_standard";
"B \NAC \NWC"5;
"S \NAC"
BN"1"114;
%"TAP"
"6","(-2850,1025)","2","mstr_standard","I91";
;
HDL_TAP"TRUE"
BODY_TYPE"PLUMBING"
CDS_LIB"mstr_standard";
"B \NAC \NWC"7;
"S \NAC"
BN"1"102;
%"TAP"
"6","(-2850,975)","2","mstr_standard","I92";
;
HDL_TAP"TRUE"
BODY_TYPE"PLUMBING"
CDS_LIB"mstr_standard";
"B \NAC \NWC"7;
"S \NAC"
BN"0"101;
%"TAP"
"6","(-2850,1075)","2","mstr_standard","I93";
;
HDL_TAP"TRUE"
BODY_TYPE"PLUMBING"
CDS_LIB"mstr_standard";
"B \NAC \NWC"7;
"S \NAC"
BN"2"103;
%"TAP"
"6","(-2850,1225)","2","mstr_standard","I94";
;
HDL_TAP"TRUE"
BODY_TYPE"PLUMBING"
CDS_LIB"mstr_standard";
"B \NAC \NWC"7;
"S \NAC"
BN"5"106;
%"TAP"
"6","(-2850,1125)","2","mstr_standard","I95";
;
HDL_TAP"TRUE"
BODY_TYPE"PLUMBING"
CDS_LIB"mstr_standard";
"B \NAC \NWC"7;
"S \NAC"
BN"3"104;
%"TAP"
"6","(-2850,1175)","2","mstr_standard","I96";
;
HDL_TAP"TRUE"
BODY_TYPE"PLUMBING"
CDS_LIB"mstr_standard";
"B \NAC \NWC"7;
"S \NAC"
BN"4"105;
%"TAP"
"6","(-2850,1275)","2","mstr_standard","I97";
;
HDL_TAP"TRUE"
BODY_TYPE"PLUMBING"
CDS_LIB"mstr_standard";
"B \NAC \NWC"7;
"S \NAC"
BN"6"107;
%"TAP"
"6","(-2850,1325)","2","mstr_standard","I98";
;
HDL_TAP"TRUE"
BODY_TYPE"PLUMBING"
CDS_LIB"mstr_standard";
"B \NAC \NWC"7;
"S \NAC"
BN"7"108;
%"TAP"
"6","(-2850,1475)","2","mstr_standard","I99";
;
HDL_TAP"TRUE"
BODY_TYPE"PLUMBING"
CDS_LIB"mstr_standard";
"B \NAC \NWC"8;
"S \NAC"
BN"1"95;
END.
